# BASEBOARD_FAB2 (Tioga Pass) — schematic netlist excerpt (pin names and nets, part order shuffled) for the footprints in the layout excerpt that follows; sources: Cadence DE-HDL packaged netlist, KiCad conversion of Wiwynn_Tioga_Pass_MB.brd

R7F37  RES  33.2 1% CHIP  pkg 0402  page 153 : A = SPI_BIOS_SOCKET_IO2 ; B = PU_BIOS_SPI_WP0_N
CT45  CAP_A  0.1UF 16V 10% X7R  pkg 0402V  page 219 : A = VR_PVDDQ_DEF_AIREF1 ; B = GND

(kicad_pcb
	(version 20260206)
	(generator "pcbnew")
	(generator_version "10.0")
	(general
		(thickness 1.6)
		(legacy_teardrops no)
	)
	(paper "A4")
	(title_block
		(title "Wiwynn_Tioga_Pass_MB.brd")
		(comment 1 "Tioga Pass / footprints 1481-1482 of 4770")
	)
	(layers
		(0 "F.Cu" signal "TOP")
		(4 "In1.Cu" signal "L2GND")
		(6 "In2.Cu" signal "L3")
		(8 "In3.Cu" signal "L4GND")
		(10 "In4.Cu" signal "L5")
		(12 "In5.Cu" signal "L6GND")
		(14 "In6.Cu" signal "L7VCC")
		(16 "In7.Cu" signal "L8VCC")
		(18 "In8.Cu" signal "L9GND")
		(20 "In9.Cu" signal "L10")
		(22 "In10.Cu" signal "L11GND")
		(24 "In11.Cu" signal "L12")
		(26 "In12.Cu" signal "L13GND")
		(2 "B.Cu" signal "BOTTOM")
		(9 "F.Adhes" user "F.Adhesive")
		(11 "B.Adhes" user "B.Adhesive")
		(13 "F.Paste" user "Package Geometry/Pastemask Top")
		(15 "B.Paste" user "Package Geometry/Pastemask Bottom")
		(5 "F.SilkS" user "Ref Des/Silkscreen Top")
		(7 "B.SilkS" user "Ref Des/Silkscreen Bottom")
		(1 "F.Mask" user "Board Geometry/Soldermask Top")
		(3 "B.Mask" user "Board Geometry/Soldermask Bottom")
		(17 "Dwgs.User" user "User.Drawings")
		(19 "Cmts.User" user "User.Comments")
		(21 "Eco1.User" user "User.Eco1")
		(23 "Eco2.User" user "User.Eco2")
		(25 "Edge.Cuts" user "Board Geometry/Outline")
		(27 "Margin" user)
		(31 "F.CrtYd" user "Package Geometry/Place Bound Top")
		(29 "B.CrtYd" user "Package Geometry/Place Bound Bottom")
		(35 "F.Fab" user "Ref Des/Assembly Top")
		(33 "B.Fab" user "Ref Des/Assembly Bottom")
	)
	(footprint ""
		(layer "F.Cu")
		(at 382.002284 -56.32958 90)
		(property "Reference" "R7F37"
			(at 0 0 90)
			(layer "F.SilkS")
			(hide yes)
			(effects
				(font
					(size 1.27 1.27)
				)
			)
		)
		(property "Value" ""
			(at 0 0 90)
			(layer "F.Fab")
			(effects
				(font
					(size 1.27 1.27)
				)
			)
		)
		(duplicate_pad_numbers_are_jumpers no)
		(fp_poly
			(pts
				(xy -0.2794 -0.1016) (xy 0.2794 -0.1016) (xy 0.2794 0.9906) (xy -0.2794 0.9906)
			)
			(stroke
				(width 0)
				(type default)
			)
			(fill no)
			(layer "F.CrtYd")
		)
		(fp_line
			(start 0.2794 -0.1016)
			(end -0.2794 -0.1016)
			(stroke
				(width 0.1)
				(type default)
			)
			(layer "F.Fab")
		)
		(fp_line
			(start -0.2794 -0.1016)
			(end -0.2794 0.9906)
			(stroke
				(width 0.1)
				(type default)
			)
			(layer "F.Fab")
		)
		(fp_line
			(start 0.2794 0.9906)
			(end 0.2794 -0.1016)
			(stroke
				(width 0.1)
				(type default)
			)
			(layer "F.Fab")
		)
		(fp_line
			(start -0.2794 0.9906)
			(end 0.2794 0.9906)
			(stroke
				(width 0.1)
				(type default)
			)
			(layer "F.Fab")
		)
		(pad "1" smd rect
			(at 0 0 90)
			(size 0.508 0.508)
			(layers "F.Cu" "F.Mask" "F.Paste")
			(net "SPI_BIOS_SOCKET_IO2")
		)
		(pad "2" smd rect
			(at 0 0.889 90)
			(size 0.508 0.508)
			(layers "F.Cu" "F.Mask" "F.Paste")
			(net "PU_BIOS_SPI_WP0_N")
		)
		(zone
			(layer "F.Cu")
			(hatch none 0.5)
			(connect_pads
				(clearance 0)
			)
			(min_thickness 0.25)
			(keepout
				(tracks allowed)
				(vias not_allowed)
				(pads allowed)
				(copperpour not_allowed)
				(footprints allowed)
			)
			(placement
				(enabled no)
				(sheetname "")
			)
			(fill
				(thermal_gap 0.5)
				(thermal_bridge_width 0.5)
				(island_removal_mode 0)
			)
			(polygon
				(pts
					(xy 382.256284 -56.07558) (xy 382.256284 -56.58358) (xy 382.637284 -56.58358) (xy 382.637284 -56.07558)
				)
			)
		)
		(zone
			(layer "F.Cu")
			(hatch none 0.5)
			(connect_pads
				(clearance 0)
			)
			(min_thickness 0.25)
			(keepout
				(tracks not_allowed)
				(vias allowed)
				(pads allowed)
				(copperpour not_allowed)
				(footprints allowed)
			)
			(placement
				(enabled no)
				(sheetname "")
			)
			(fill
				(thermal_gap 0.5)
				(thermal_bridge_width 0.5)
				(island_removal_mode 0)
			)
			(polygon
				(pts
					(xy 382.637284 -56.07558) (xy 382.637284 -56.58358) (xy 382.256284 -56.58358) (xy 382.256284 -56.07558)
				)
			)
		)
	)
	(footprint ""
		(layer "F.Cu")
		(at 351.505266 -156.4005 180)
		(property "Reference" "CT45"
			(at 0.7366 1.85293 0)
			(unlocked yes)
			(layer "F.SilkS")
			(effects
				(font
					(size 0.7874 0.5842)
					(thickness 0.1524)
				)
				(justify left)
			)
		)
		(property "Value" ""
			(at 0 0 180)
			(layer "F.Fab")
			(effects
				(font
					(size 1.27 1.27)
				)
			)
		)
		(duplicate_pad_numbers_are_jumpers no)
		(fp_poly
			(pts
				(xy 0.3048 -0.1016) (xy 0.3048 0.9906) (xy -0.3048 0.9906) (xy -0.3048 -0.1016)
			)
			(stroke
				(width 0)
				(type default)
			)
			(fill no)
			(layer "F.CrtYd")
		)
		(fp_line
			(start 0.3048 0.9906)
			(end 0.3048 -0.1016)
			(stroke
				(width 0.1)
				(type default)
			)
			(layer "F.Fab")
		)
		(fp_line
			(start 0.3048 -0.1016)
			(end -0.3048 -0.1016)
			(stroke
				(width 0.1)
				(type default)
			)
			(layer "F.Fab")
		)
		(fp_line
			(start -0.3048 0.9906)
			(end 0.3048 0.9906)
			(stroke
				(width 0.1)
				(type default)
			)
			(layer "F.Fab")
		)
		(fp_line
			(start -0.3048 -0.1016)
			(end -0.3048 0.9906)
			(stroke
				(width 0.1)
				(type default)
			)
			(layer "F.Fab")
		)
		(pad "1" smd rect
			(at 0 0 180)
			(size 0.508 0.508)
			(layers "F.Cu" "F.Mask" "F.Paste")
			(net "VR_PVDDQ_DEF_AIREF1")
		)
		(pad "2" smd rect
			(at 0 0.889 180)
			(size 0.508 0.508)
			(layers "F.Cu" "F.Mask" "F.Paste")
			(net "GND")
		)
		(zone
			(layer "F.Cu")
			(hatch none 0.5)
			(connect_pads
				(clearance 0)
			)
			(min_thickness 0.25)
			(keepout
				(tracks not_allowed)
				(vias allowed)
				(pads allowed)
				(copperpour not_allowed)
				(footprints allowed)
			)
			(placement
				(enabled no)
				(sheetname "")
			)
			(fill
				(thermal_gap 0.5)
				(thermal_bridge_width 0.5)
				(island_removal_mode 0)
			)
			(polygon
				(pts
					(xy 351.759266 -157.0355) (xy 351.251266 -157.0355) (xy 351.251266 -156.6545) (xy 351.759266 -156.6545)
				)
			)
		)
		(zone
			(layer "F.Cu")
			(hatch none 0.5)
			(connect_pads
				(clearance 0)
			)
			(min_thickness 0.25)
			(keepout
				(tracks allowed)
				(vias not_allowed)
				(pads allowed)
				(copperpour not_allowed)
				(footprints allowed)
			)
			(placement
				(enabled no)
				(sheetname "")
			)
			(fill
				(thermal_gap 0.5)
				(thermal_bridge_width 0.5)
				(island_removal_mode 0)
			)
			(polygon
				(pts
					(xy 351.759266 -156.6545) (xy 351.251266 -156.6545) (xy 351.251266 -157.0355) (xy 351.759266 -157.0355)
				)
			)
		)
	)
)
